# SCM (Grand Teton) — schematic netlist excerpt (pin names and nets, part order shuffled) for the footprints in the layout excerpt that follows; sources: Cadence DE-HDL packaged netlist, KiCad conversion of 12092022_DA0F0TMDCD0_F0T_Management_Board_D_brd_V3_OCP.brd

R607  Q_RES  4.7K 1% CHIP  pkg 0402LF  page 42 : A = P3V3_AUX ; B = BMC_CPLD_GPIO_12

U58  MC74VHC1G32DTT1G  IC  pkg SOT23-5_0-95_3X1-5  page 22
  IN_B  = RST_BMC_SELF_HW_R3
  IN_A  = RST_BMC_HW_R1
  GND  = GND
  OUT_Y  = RST_BMC_HW_OUT
  VCC  = P3V3_AUX

(kicad_pcb
	(version 20260206)
	(generator "pcbnew")
	(generator_version "10.0")
	(general
		(thickness 1.6)
		(legacy_teardrops no)
	)
	(paper "A4")
	(title_block
		(title "12092022_DA0F0TMDCD0_F0T_Management_Board_D_brd_V3_OCP.brd")
		(comment 1 "Grand Teton / footprints 1353-1354 of 1440")
	)
	(layers
		(0 "F.Cu" signal "TOP")
		(4 "In1.Cu" signal "GND")
		(6 "In2.Cu" signal "IN1")
		(8 "In3.Cu" signal "GND1")
		(10 "In4.Cu" signal "IN2")
		(12 "In5.Cu" signal "VCC")
		(14 "In6.Cu" signal "VCC1")
		(16 "In7.Cu" signal "IN3")
		(18 "In8.Cu" signal "GND2")
		(20 "In9.Cu" signal "IN4")
		(22 "In10.Cu" signal "GND3")
		(2 "B.Cu" signal "BOTTOM")
		(9 "F.Adhes" user "F.Adhesive")
		(11 "B.Adhes" user "B.Adhesive")
		(13 "F.Paste" user "Package Geometry/Pastemask Top")
		(15 "B.Paste" user "Package Geometry/Pastemask Bottom")
		(5 "F.SilkS" user "Ref Des/Silkscreen Top")
		(7 "B.SilkS" user "Ref Des/Silkscreen Bottom")
		(1 "F.Mask" user "Board Geometry/Soldermask Top")
		(3 "B.Mask" user "Board Geometry/Soldermask Bottom")
		(17 "Dwgs.User" user "User.Drawings")
		(19 "Cmts.User" user "User.Comments")
		(21 "Eco1.User" user "User.Eco1")
		(23 "Eco2.User" user "User.Eco2")
		(25 "Edge.Cuts" user "Board Geometry/Outline")
		(27 "Margin" user)
		(31 "F.CrtYd" user "Package Geometry/Place Bound Top")
		(29 "B.CrtYd" user "Package Geometry/Place Bound Bottom")
		(35 "F.Fab" user "Ref Des/Assembly Top")
		(33 "B.Fab" user "Ref Des/Assembly Bottom")
	)
	(footprint ""
		(layer "B.Cu")
		(at 33.1089 -97.1042 90)
		(property "Reference" "U58"
			(at 0.1778 2.17043 270)
			(unlocked yes)
			(layer "B.SilkS")
			(effects
				(font
					(size 0.7874 0.5842)
					(thickness 0.1524)
				)
				(justify mirror)
			)
		)
		(property "Value" ""
			(at 0 0 90)
			(layer "B.Fab")
			(effects
				(font
					(size 1.27 1.27)
				)
				(justify mirror)
			)
		)
		(duplicate_pad_numbers_are_jumpers no)
		(fp_line
			(start 1.834896 -1.575054)
			(end 0.508 -1.575054)
			(stroke
				(width 0.1524)
				(type default)
			)
			(layer "B.SilkS")
		)
		(fp_line
			(start 0.508 -1.575054)
			(end 0 -1.016)
			(stroke
				(width 0.1524)
				(type default)
			)
			(layer "B.SilkS")
		)
		(fp_line
			(start -0.508 -1.575054)
			(end -1.834896 -1.575054)
			(stroke
				(width 0.1524)
				(type default)
			)
			(layer "B.SilkS")
		)
		(fp_line
			(start -1.834896 -1.575054)
			(end -1.834896 1.575054)
			(stroke
				(width 0.1524)
				(type default)
			)
			(layer "B.SilkS")
		)
		(fp_line
			(start 0 -1.016)
			(end -0.508 -1.575054)
			(stroke
				(width 0.1524)
				(type default)
			)
			(layer "B.SilkS")
		)
		(fp_line
			(start 1.834896 1.575054)
			(end 1.834896 -1.575054)
			(stroke
				(width 0.1524)
				(type default)
			)
			(layer "B.SilkS")
		)
		(fp_line
			(start -1.834896 1.575054)
			(end 1.834896 1.575054)
			(stroke
				(width 0.1524)
				(type default)
			)
			(layer "B.SilkS")
		)
		(fp_poly
			(pts
				(xy 3.003296 -1.45796) (xy 3.003296 -0.44196) (xy 1.987296 -0.94996)
			)
			(stroke
				(width 0)
				(type default)
			)
			(fill yes)
			(layer "B.SilkS")
		)
		(fp_line
			(start 0.824992 -1.575054)
			(end -0.824992 -1.575054)
			(stroke
				(width 0.1)
				(type default)
			)
			(layer "B.Fab")
		)
		(fp_line
			(start -0.824992 -1.575054)
			(end -0.824992 1.575054)
			(stroke
				(width 0.1)
				(type default)
			)
			(layer "B.Fab")
		)
		(fp_line
			(start 0.824992 1.575054)
			(end 0.824992 -1.575054)
			(stroke
				(width 0.1)
				(type default)
			)
			(layer "B.Fab")
		)
		(fp_line
			(start -0.824992 1.575054)
			(end 0.824992 1.575054)
			(stroke
				(width 0.1)
				(type default)
			)
			(layer "B.Fab")
		)
		(fp_poly
			(pts
				(xy 3.003296 -1.45796) (xy 3.003296 -0.44196) (xy 1.987296 -0.94996)
			)
			(stroke
				(width 0)
				(type default)
			)
			(fill yes)
			(layer "B.Fab")
		)
		(pad "1" smd rect
			(at 1.199896 -0.94996)
			(size 0.7112 1.016)
			(layers "B.Cu" "B.Mask" "B.Paste")
			(net "RST_BMC_SELF_HW_R3")
		)
		(pad "2" smd rect
			(at 1.199896 0)
			(size 0.7112 1.016)
			(layers "B.Cu" "B.Mask" "B.Paste")
			(net "RST_BMC_HW_R1")
		)
		(pad "3" smd rect
			(at 1.199896 0.94996)
			(size 0.7112 1.016)
			(layers "B.Cu" "B.Mask" "B.Paste")
			(net "GND")
		)
		(pad "4" smd rect
			(at -1.199896 0.94996)
			(size 0.7112 1.016)
			(layers "B.Cu" "B.Mask" "B.Paste")
			(net "RST_BMC_HW_OUT")
		)
		(pad "5" smd rect
			(at -1.199896 -0.94996)
			(size 0.7112 1.016)
			(layers "B.Cu" "B.Mask" "B.Paste")
			(net "P3V3_AUX")
		)
	)
	(footprint ""
		(layer "B.Cu")
		(at 10.40892 -94.6404 90)
		(property "Reference" "R607"
			(at 0 0 90)
			(layer "B.SilkS")
			(hide yes)
			(effects
				(font
					(size 1.27 1.27)
				)
				(justify mirror)
			)
		)
		(property "Value" ""
			(at 0 0 90)
			(layer "B.Fab")
			(effects
				(font
					(size 1.27 1.27)
				)
				(justify mirror)
			)
		)
		(duplicate_pad_numbers_are_jumpers no)
		(fp_line
			(start 0.7874 -0.4064)
			(end -0.7874 -0.4064)
			(stroke
				(width 0.1524)
				(type default)
			)
			(layer "B.SilkS")
		)
		(fp_line
			(start -0.7874 -0.4064)
			(end -0.7874 0.4064)
			(stroke
				(width 0.1524)
				(type default)
			)
			(layer "B.SilkS")
		)
		(fp_line
			(start 0.7874 0.4064)
			(end 0.7874 -0.4064)
			(stroke
				(width 0.1524)
				(type default)
			)
			(layer "B.SilkS")
		)
		(fp_line
			(start -0.7874 0.4064)
			(end 0.7874 0.4064)
			(stroke
				(width 0.1524)
				(type default)
			)
			(layer "B.SilkS")
		)
		(fp_line
			(start 0.67945 -0.305054)
			(end 0.12065 -0.305054)
			(stroke
				(width 0.1)
				(type default)
			)
			(layer "B.Fab")
		)
		(fp_line
			(start 0.12065 -0.305054)
			(end 0.12065 -0.2794)
			(stroke
				(width 0.1)
				(type default)
			)
			(layer "B.Fab")
		)
		(fp_line
			(start -0.12065 -0.3048)
			(end -0.67945 -0.3048)
			(stroke
				(width 0.1)
				(type default)
			)
			(layer "B.Fab")
		)
		(fp_line
			(start -0.67945 -0.3048)
			(end -0.67945 0.3048)
			(stroke
				(width 0.1)
				(type default)
			)
			(layer "B.Fab")
		)
		(fp_line
			(start 0.12065 -0.2794)
			(end -0.12065 -0.2794)
			(stroke
				(width 0.1)
				(type default)
			)
			(layer "B.Fab")
		)
		(fp_line
			(start -0.12065 -0.2794)
			(end -0.12065 -0.3048)
			(stroke
				(width 0.1)
				(type default)
			)
			(layer "B.Fab")
		)
		(fp_line
			(start 0.12065 0.2794)
			(end 0.12065 0.3048)
			(stroke
				(width 0.1)
				(type default)
			)
			(layer "B.Fab")
		)
		(fp_line
			(start -0.120396 0.2794)
			(end 0.12065 0.2794)
			(stroke
				(width 0.1)
				(type default)
			)
			(layer "B.Fab")
		)
		(fp_line
			(start 0.67945 0.3048)
			(end 0.67945 -0.305054)
			(stroke
				(width 0.1)
				(type default)
			)
			(layer "B.Fab")
		)
		(fp_line
			(start 0.12065 0.3048)
			(end 0.67945 0.3048)
			(stroke
				(width 0.1)
				(type default)
			)
			(layer "B.Fab")
		)
		(fp_line
			(start -0.120396 0.3048)
			(end -0.120396 0.2794)
			(stroke
				(width 0.1)
				(type default)
			)
			(layer "B.Fab")
		)
		(fp_line
			(start -0.67945 0.3048)
			(end -0.120396 0.3048)
			(stroke
				(width 0.1)
				(type default)
			)
			(layer "B.Fab")
		)
		(pad "1" smd circle
			(at 0.40005 0 270)
			(size 0 0)
			(layers "B.Cu" "B.Mask" "B.Paste")
			(net "P3V3_AUX")
		)
		(pad "2" smd circle
			(at -0.40005 0 270)
			(size 0 0)
			(layers "B.Cu" "B.Mask" "B.Paste")
			(net "BMC_CPLD_GPIO_12")
		)
	)
)
